FILE_TYPE = MACRO_DRAWING;
SET COLOR_WIRE YELLOW;
SET COLOR_PROP MONO;
SET COLOR_DOT WHITE;
SET COLOR_ARC YELLOW;
SET COLOR_BODY GREEN;
SET COLOR_NOTE MONO;
SET PROP_DISPLAY VALUE;
SET PAGE_NUMBER P168;
FORCEADD OFFPAGE..1
(-7525 2750);
FORCEPROP 2 LAST $XR1 247 
J 0
(-7897 2750);
DISPLAY 0.638298 (-7897 2750);
PAINT MONO (-7897 2750);
FORCEPROP 2 LAST $XR0 155 
J 0
(-7777 2750);
DISPLAY 0.638298 (-7777 2750);
PAINT MONO (-7777 2750);
FORCEPROP 2 LAST CDS_LIB mstr_standard
J 0
(-7525 2750);
PAINT ORANGE (-7525 2750);
DISPLAY INVISIBLE (-7525 2750);
FORCEPROP 1 LAST OFFPAGE TRUE
J 0
(-7200 2625);
DISPLAY 0.872340 (-7200 2625);
PAINT GREEN (-7200 2625);
DISPLAY INVISIBLE (-7200 2625);
FORCEPROP 1 LAST COMMENT_BODY TRUE
J 0
(-7400 2650);
DISPLAY 0.872340 (-7400 2650);
PAINT GREEN (-7400 2650);
DISPLAY INVISIBLE (-7400 2650);
FORCEPROP 2 LAST PATH I1
J 0
(-7475 2825);
DISPLAY 1.021277 (-7475 2825);
PAINT ORANGE (-7475 2825);
DISPLAY INVISIBLE (-7475 2825);
FORCEADD RES..2
(-3400 3050);
FORCEPROP 1 LAST LOCATION R1L36
J 0
(-3355 3175);
DISPLAY 0.617021 (-3355 3175);
PAINT AQUA (-3355 3175);
FORCEPROP 1 LAST VALUE 1.00K
J 0
(-3355 3125);
DISPLAY 0.617021 (-3355 3125);
PAINT SKYBLUE (-3355 3125);
FORCEPROP 1 LAST TOLERANCE 1%
J 0
(-3355 3075);
DISPLAY 0.617021 (-3355 3075);
PAINT SKYBLUE (-3355 3075);
FORCEPROP 1 LASTPIN (-3400 2950) $PN 2
J 0
(-3395 2960);
DISPLAY 0.617021 (-3395 2960);
PAINT ORANGE (-3395 2960);
FORCEPROP 1 LASTPIN (-3400 3150) $PN 1
J 0
(-3395 3112);
DISPLAY 0.617021 (-3395 3112);
PAINT ORANGE (-3395 3112);
FORCEPROP 1 LAST MATERIAL CHIP
J 0
(-3360 2975);
DISPLAY 0.617021 (-3360 2975);
PAINT SKYBLUE (-3360 2975);
FORCEPROP 1 LAST WATTAGE 1/16W
J 0
(-3360 3025);
DISPLAY 0.617021 (-3360 3025);
PAINT SKYBLUE (-3360 3025);
FORCEPROP 1 LAST PART_NUMBER G21796-026
J 0
(-3360 2925);
DISPLAY 0.617021 (-3360 2925);
PAINT BLUE (-3360 2925);
FORCEPROP 1 LAST PACK_TYPE 0402
J 0
(-3360 2875);
DISPLAY 0.617021 (-3360 2875);
PAINT SKYBLUE (-3360 2875);
FORCEPROP 2 LAST SEC_TYPE 0402
J 0
(-3350 3275);
DISPLAY 1.021277 (-3350 3275);
PAINT ORANGE (-3350 3275);
DISPLAY INVISIBLE (-3350 3275);
FORCEPROP 2 LAST CDS_LIB mstr_discrete
J 0
(-3400 3050);
PAINT ORANGE (-3400 3050);
DISPLAY INVISIBLE (-3400 3050);
FORCEPROP 2 LAST BOM_COST DEBUG
J 0
(-3350 3275);
DISPLAY 1.021277 (-3350 3275);
PAINT ORANGE (-3350 3275);
DISPLAY INVISIBLE (-3350 3275);
FORCEPROP 2 LAST SEC 1
J 0
(-3350 3275);
DISPLAY 0.680851 (-3350 3275);
PAINT MONO (-3350 3275);
DISPLAY INVISIBLE (-3350 3275);
FORCEPROP 2 LAST CDS_LOCATION R1L36
J 0
(-3355 3175);
DISPLAY 0.617021 (-3355 3175);
PAINT AQUA (-3355 3175);
DISPLAY INVISIBLE (-3355 3175);
FORCEPROP 2 LAST ROOM UART_MUX
J 0
(-3350 3225);
DISPLAY 1.021277 (-3350 3225);
PAINT ORANGE (-3350 3225);
DISPLAY INVISIBLE (-3350 3225);
FORCEPROP 1 LAST PATH I11
J 0
(-3350 3225);
DISPLAY 0.978723 (-3350 3225);
PAINT WHITE (-3350 3225);
DISPLAY INVISIBLE (-3350 3225);
FORCEADD GND..1
(-3400 2525);
FORCEPROP 3 LASTPIN (-3400 2575) SIG_NAME GND\g
J 0
(-3390 2585);
DISPLAY 0.659574 (-3390 2585);
PAINT MONO (-3390 2585);
DISPLAY INVISIBLE (-3390 2585);
FORCEPROP 1 LAST HDL_POWER GND
J 0
(-3400 2675);
DISPLAY 0.872340 (-3400 2675);
PAINT GREEN (-3400 2675);
DISPLAY INVISIBLE (-3400 2675);
FORCEPROP 1 LAST BODY_TYPE PLUMBING
J 0
(-3445 2482);
DISPLAY 0.340426 (-3445 2482);
PAINT GREEN (-3445 2482);
DISPLAY INVISIBLE (-3445 2482);
FORCEPROP 1 LAST VOLTAGE 0.0V
J 0
(-3445 2482);
DISPLAY 0.340426 (-3445 2482);
PAINT SKYBLUE (-3445 2482);
DISPLAY INVISIBLE (-3445 2482);
FORCEPROP 1 LAST SIZE 1B
J 0
(-3325 2475);
DISPLAY 0.872340 (-3325 2475);
PAINT AQUA (-3325 2475);
DISPLAY INVISIBLE (-3325 2475);
FORCEPROP 2 LAST CDS_LIB mstr_symbols
J 0
(-3400 2525);
PAINT ORANGE (-3400 2525);
DISPLAY INVISIBLE (-3400 2525);
FORCEPROP 1 LAST PATH I14
J 0
(-3325 2525);
DISPLAY 0.872340 (-3325 2525);
PAINT AQUA (-3325 2525);
DISPLAY INVISIBLE (-3325 2525);
FORCEADD FET_N_DUAL..5
(-1525 4425);
FORCEPROP 1 LAST LOCATION Q1L4
J 0
(-1325 4425);
DISPLAY 0.617021 (-1325 4425);
PAINT AQUA (-1325 4425);
FORCEPROP 1 LAST PART_NUMBER D24280-001
J 0
(-1325 4225);
DISPLAY 0.617021 (-1325 4225);
PAINT BLUE (-1325 4225);
FORCEPROP 1 LAST VALUE 2N7002DW
J 0
(-1325 4375);
DISPLAY 0.617021 (-1325 4375);
PAINT SKYBLUE (-1325 4375);
FORCEPROP 1 LAST MATERIAL FET
J 0
(-1325 4325);
DISPLAY 0.617021 (-1325 4325);
PAINT SKYBLUE (-1325 4325);
FORCEPROP 1 LASTPIN (-1525 4225) $PN 4
J 2
(-1467 4225);
DISPLAY 0.617021 (-1467 4225);
PAINT WHITE (-1467 4225);
FORCEPROP 1 LASTPIN (-1725 4325) $PN 5
J 2
(-1722 4340);
DISPLAY 0.617021 (-1722 4340);
PAINT WHITE (-1722 4340);
FORCEPROP 1 LASTPIN (-1525 4625) $PN 3
J 2
(-1472 4590);
DISPLAY 0.617021 (-1472 4590);
PAINT WHITE (-1472 4590);
FORCEPROP 1 LAST PACK_TYPE SMLF
J 0
(-1325 4275);
DISPLAY 0.978723 (-1325 4275);
PAINT SKYBLUE (-1325 4275);
DISPLAY INVISIBLE (-1325 4275);
FORCEPROP 2 LAST BOM_COST DEBUG
J 0
(-1325 4525);
DISPLAY 1.021277 (-1325 4525);
PAINT ORANGE (-1325 4525);
DISPLAY INVISIBLE (-1325 4525);
FORCEPROP 2 LAST CDS_LIB mstr_discrete
J 0
(-1525 4425);
PAINT MONO (-1525 4425);
DISPLAY INVISIBLE (-1525 4425);
FORCEPROP 2 LAST SEC_TYPE SMLF
J 0
(-1325 4525);
DISPLAY 1.021277 (-1325 4525);
PAINT ORANGE (-1325 4525);
DISPLAY INVISIBLE (-1325 4525);
FORCEPROP 2 LAST SEC 2
J 0
(-1325 4525);
DISPLAY 0.680851 (-1325 4525);
PAINT MONO (-1325 4525);
DISPLAY INVISIBLE (-1325 4525);
FORCEPROP 2 LAST CDS_LOCATION Q1L4
J 0
(-1325 4425);
DISPLAY 0.617021 (-1325 4425);
PAINT AQUA (-1325 4425);
DISPLAY INVISIBLE (-1325 4425);
FORCEPROP 1 LAST PATH I18
J 0
(-1325 4475);
DISPLAY 0.978723 (-1325 4475);
PAINT BLUE (-1325 4475);
DISPLAY INVISIBLE (-1325 4475);
FORCEPROP 2 LAST ROOM UART_MUX
J 0
(-1325 4475);
DISPLAY 1.021277 (-1325 4475);
PAINT ORANGE (-1325 4475);
DISPLAY INVISIBLE (-1325 4475);
FORCEADD FET_N_DUAL..5
(-2425 3000);
FORCEPROP 1 LASTPIN (-2425 2800) $PN 1
J 2
(-2367 2800);
DISPLAY 0.617021 (-2367 2800);
PAINT WHITE (-2367 2800);
FORCEPROP 1 LASTPIN (-2625 2900) $PN 2
J 2
(-2622 2915);
DISPLAY 0.617021 (-2622 2915);
PAINT WHITE (-2622 2915);
FORCEPROP 1 LAST MATERIAL FET
J 0
(-2225 2900);
DISPLAY 0.617021 (-2225 2900);
PAINT SKYBLUE (-2225 2900);
FORCEPROP 1 LASTPIN (-2425 3200) $PN 6
J 2
(-2372 3165);
DISPLAY 0.617021 (-2372 3165);
PAINT WHITE (-2372 3165);
FORCEPROP 1 LAST VALUE 2N7002DW
J 0
(-2225 2950);
DISPLAY 0.617021 (-2225 2950);
PAINT SKYBLUE (-2225 2950);
FORCEPROP 1 LAST LOCATION Q1L4
J 0
(-2225 3000);
DISPLAY 0.617021 (-2225 3000);
PAINT AQUA (-2225 3000);
FORCEPROP 1 LAST PART_NUMBER D24280-001
J 0
(-2225 2800);
DISPLAY 0.617021 (-2225 2800);
PAINT BLUE (-2225 2800);
FORCEPROP 2 LAST ROOM UART_MUX
J 0
(-2225 3050);
DISPLAY 1.021277 (-2225 3050);
PAINT ORANGE (-2225 3050);
DISPLAY INVISIBLE (-2225 3050);
FORCEPROP 1 LAST PATH I19
J 0
(-2225 3050);
DISPLAY 0.978723 (-2225 3050);
PAINT BLUE (-2225 3050);
DISPLAY INVISIBLE (-2225 3050);
FORCEPROP 2 LAST CDS_LOCATION Q1L4
J 0
(-2225 3000);
DISPLAY 0.617021 (-2225 3000);
PAINT AQUA (-2225 3000);
DISPLAY INVISIBLE (-2225 3000);
FORCEPROP 2 LAST SEC 1
J 0
(-2225 3100);
DISPLAY 0.680851 (-2225 3100);
PAINT MONO (-2225 3100);
DISPLAY INVISIBLE (-2225 3100);
FORCEPROP 2 LAST SEC_TYPE SMLF
J 0
(-2225 3100);
DISPLAY 1.021277 (-2225 3100);
PAINT ORANGE (-2225 3100);
DISPLAY INVISIBLE (-2225 3100);
FORCEPROP 2 LAST CDS_LIB mstr_discrete
J 0
(-2425 3000);
PAINT MONO (-2425 3000);
DISPLAY INVISIBLE (-2425 3000);
FORCEPROP 2 LAST BOM_COST DEBUG
J 0
(-2225 3100);
DISPLAY 1.021277 (-2225 3100);
PAINT ORANGE (-2225 3100);
DISPLAY INVISIBLE (-2225 3100);
FORCEPROP 1 LAST PACK_TYPE SMLF
J 0
(-2225 2850);
DISPLAY 0.978723 (-2225 2850);
PAINT SKYBLUE (-2225 2850);
DISPLAY INVISIBLE (-2225 2850);
FORCEADD DIODE..1
(-6325 2750);
FORCEPROP 1 LAST VALUE 1N4148W
J 0
(-6350 2625);
DISPLAY 0.617021 (-6350 2625);
PAINT SKYBLUE (-6350 2625);
FORCEPROP 1 LASTPIN (-6425 2750) $PN 2
J 2
(-6390 2760);
DISPLAY 0.617021 (-6390 2760);
PAINT AQUA (-6390 2760);
FORCEPROP 1 LASTPIN (-6225 2750) $PN 1
J 0
(-6260 2760);
DISPLAY 0.617021 (-6260 2760);
PAINT AQUA (-6260 2760);
FORCEPROP 1 LAST MATERIAL IC
J 0
(-6350 2572);
DISPLAY 0.617021 (-6350 2572);
PAINT SKYBLUE (-6350 2572);
FORCEPROP 1 LAST PACK_TYPE SM
J 0
(-6350 2510);
DISPLAY 0.617021 (-6350 2510);
PAINT SKYBLUE (-6350 2510);
FORCEPROP 1 LAST PART_NUMBER D89194-001
J 0
(-6350 2850);
DISPLAY 0.617021 (-6350 2850);
PAINT BLUE (-6350 2850);
FORCEPROP 1 LAST LOCATION CR1L1
J 0
(-6352 2906);
DISPLAY 0.617021 (-6352 2906);
PAINT AQUA (-6352 2906);
FORCEPROP 2 LAST ROOM UART_MUX
J 0
(-6350 2950);
DISPLAY 1.021277 (-6350 2950);
PAINT ORANGE (-6350 2950);
DISPLAY INVISIBLE (-6350 2950);
FORCEPROP 1 LAST PATH I2
J 0
(-6345 2960);
DISPLAY 0.978723 (-6345 2960);
PAINT PINK (-6345 2960);
DISPLAY INVISIBLE (-6345 2960);
FORCEPROP 2 LAST CDS_LOCATION CR1L1
J 0
(-6352 2906);
DISPLAY 0.617021 (-6352 2906);
PAINT AQUA (-6352 2906);
DISPLAY INVISIBLE (-6352 2906);
FORCEPROP 2 LAST SEC 1
J 0
(-6325 3025);
DISPLAY 0.680851 (-6325 3025);
PAINT MONO (-6325 3025);
DISPLAY INVISIBLE (-6325 3025);
FORCEPROP 2 LAST BOM_COST DEBUG
J 0
(-6350 3000);
DISPLAY 1.021277 (-6350 3000);
PAINT ORANGE (-6350 3000);
DISPLAY INVISIBLE (-6350 3000);
FORCEPROP 2 LAST CDS_LIB mstr_discrete
J 0
(-6325 2750);
PAINT ORANGE (-6325 2750);
DISPLAY INVISIBLE (-6325 2750);
FORCEPROP 2 LAST SEC_TYPE SM
J 0
(-6325 3025);
DISPLAY 1.021277 (-6325 3025);
PAINT ORANGE (-6325 3025);
DISPLAY INVISIBLE (-6325 3025);
FORCEADD RES..2
(-2425 3425);
FORCEPROP 1 LASTPIN (-2425 3325) $PN 2
J 0
(-2420 3335);
DISPLAY 0.617021 (-2420 3335);
PAINT ORANGE (-2420 3335);
FORCEPROP 1 LAST TOLERANCE 1%
J 0
(-2380 3450);
DISPLAY 0.617021 (-2380 3450);
PAINT SKYBLUE (-2380 3450);
FORCEPROP 1 LAST LOCATION R1L38
J 0
(-2380 3550);
DISPLAY 0.617021 (-2380 3550);
PAINT AQUA (-2380 3550);
FORCEPROP 1 LAST VALUE 1.00K
J 0
(-2380 3500);
DISPLAY 0.617021 (-2380 3500);
PAINT SKYBLUE (-2380 3500);
FORCEPROP 1 LASTPIN (-2425 3525) $PN 1
J 0
(-2420 3487);
DISPLAY 0.617021 (-2420 3487);
PAINT ORANGE (-2420 3487);
FORCEPROP 1 LAST WATTAGE 1/16W
J 0
(-2385 3400);
DISPLAY 0.617021 (-2385 3400);
PAINT SKYBLUE (-2385 3400);
FORCEPROP 1 LAST MATERIAL CHIP
J 0
(-2385 3350);
DISPLAY 0.617021 (-2385 3350);
PAINT SKYBLUE (-2385 3350);
FORCEPROP 1 LAST PART_NUMBER G21796-026
J 0
(-2385 3300);
DISPLAY 0.617021 (-2385 3300);
PAINT BLUE (-2385 3300);
FORCEPROP 1 LAST PACK_TYPE 0402
J 0
(-2385 3250);
DISPLAY 0.617021 (-2385 3250);
PAINT SKYBLUE (-2385 3250);
FORCEPROP 2 LAST ROOM UART_MUX
J 0
(-2375 3600);
DISPLAY 1.021277 (-2375 3600);
PAINT ORANGE (-2375 3600);
DISPLAY INVISIBLE (-2375 3600);
FORCEPROP 1 LAST PATH I22
J 0
(-2375 3600);
DISPLAY 0.978723 (-2375 3600);
PAINT WHITE (-2375 3600);
DISPLAY INVISIBLE (-2375 3600);
FORCEPROP 2 LAST CDS_LOCATION R1L38
J 0
(-2380 3550);
DISPLAY 0.617021 (-2380 3550);
PAINT AQUA (-2380 3550);
DISPLAY INVISIBLE (-2380 3550);
FORCEPROP 2 LAST SEC 1
J 0
(-2375 3650);
DISPLAY 0.680851 (-2375 3650);
PAINT MONO (-2375 3650);
DISPLAY INVISIBLE (-2375 3650);
FORCEPROP 2 LAST BOM_COST DEBUG
J 0
(-2375 3650);
DISPLAY 1.021277 (-2375 3650);
PAINT ORANGE (-2375 3650);
DISPLAY INVISIBLE (-2375 3650);
FORCEPROP 2 LAST CDS_LIB mstr_discrete
J 0
(-2425 3425);
PAINT ORANGE (-2425 3425);
DISPLAY INVISIBLE (-2425 3425);
FORCEPROP 2 LAST SEC_TYPE 0402
J 0
(-2375 3650);
DISPLAY 1.021277 (-2375 3650);
PAINT ORANGE (-2375 3650);
DISPLAY INVISIBLE (-2375 3650);
FORCEADD P3V3_STBY..1
(-2425 3625);
FORCEPROP 3 LASTPIN (-2425 3575) SIG_NAME P3V3_STBY\g
J 0
(-2415 3585);
DISPLAY 0.659574 (-2415 3585);
PAINT MONO (-2415 3585);
DISPLAY INVISIBLE (-2415 3585);
FORCEPROP 1 LAST HDL_POWER P3V3_STBY
J 0
(-2725 3500);
DISPLAY 0.872340 (-2725 3500);
PAINT ORANGE (-2725 3500);
DISPLAY INVISIBLE (-2725 3500);
FORCEPROP 1 LAST BODY_TYPE PLUMBING
J 0
(-2470 3582);
DISPLAY 0.340426 (-2470 3582);
PAINT GREEN (-2470 3582);
DISPLAY INVISIBLE (-2470 3582);
FORCEPROP 1 LAST PATH I24
J 0
(-2380 3627);
DISPLAY 0.340426 (-2380 3627);
PAINT GREEN (-2380 3627);
DISPLAY INVISIBLE (-2380 3627);
FORCEPROP 1 LAST SIZE 1B
J 0
(-2380 3647);
DISPLAY 0.340426 (-2380 3647);
PAINT GREEN (-2380 3647);
DISPLAY INVISIBLE (-2380 3647);
FORCEPROP 2 LAST CDS_LIB mstr_symbols
J 0
(-2425 3625);
PAINT ORANGE (-2425 3625);
DISPLAY INVISIBLE (-2425 3625);
FORCEPROP 1 LAST VOLTAGE 3.3V
J 0
(-2470 3582);
DISPLAY 0.340426 (-2470 3582);
PAINT SKYBLUE (-2470 3582);
DISPLAY INVISIBLE (-2470 3582);
FORCEADD GND..1
(-2425 2675);
FORCEPROP 3 LASTPIN (-2425 2725) SIG_NAME GND\g
J 0
(-2415 2735);
DISPLAY 0.659574 (-2415 2735);
PAINT MONO (-2415 2735);
DISPLAY INVISIBLE (-2415 2735);
FORCEPROP 1 LAST HDL_POWER GND
J 0
(-2425 2825);
DISPLAY 0.872340 (-2425 2825);
PAINT GREEN (-2425 2825);
DISPLAY INVISIBLE (-2425 2825);
FORCEPROP 1 LAST BODY_TYPE PLUMBING
J 0
(-2470 2632);
DISPLAY 0.340426 (-2470 2632);
PAINT GREEN (-2470 2632);
DISPLAY INVISIBLE (-2470 2632);
FORCEPROP 1 LAST PATH I26
J 0
(-2350 2675);
DISPLAY 0.872340 (-2350 2675);
PAINT AQUA (-2350 2675);
DISPLAY INVISIBLE (-2350 2675);
FORCEPROP 1 LAST VOLTAGE 0.0V
J 0
(-2470 2632);
DISPLAY 0.340426 (-2470 2632);
PAINT SKYBLUE (-2470 2632);
DISPLAY INVISIBLE (-2470 2632);
FORCEPROP 2 LAST CDS_LIB mstr_symbols
J 0
(-2425 2675);
PAINT ORANGE (-2425 2675);
DISPLAY INVISIBLE (-2425 2675);
FORCEPROP 1 LAST SIZE 1B
J 0
(-2350 2625);
DISPLAY 0.872340 (-2350 2625);
PAINT AQUA (-2350 2625);
DISPLAY INVISIBLE (-2350 2625);
FORCEADD OFFPAGE..2
(-550 3225);
FORCEPROP 2 LAST $XR1 146 
J 0
(-241 3225);
DISPLAY 0.638298 (-241 3225);
PAINT MONO (-241 3225);
FORCEPROP 2 LAST $XR0 120 
J 0
(-361 3225);
DISPLAY 0.638298 (-361 3225);
PAINT MONO (-361 3225);
FORCEPROP 1 LAST COMMENT_BODY TRUE
J 0
(-595 3130);
DISPLAY 0.872340 (-595 3130);
PAINT GREEN (-595 3130);
DISPLAY INVISIBLE (-595 3130);
FORCEPROP 1 LAST OFFPAGE TRUE
J 0
(-225 3100);
DISPLAY 0.872340 (-225 3100);
PAINT GREEN (-225 3100);
DISPLAY INVISIBLE (-225 3100);
FORCEPROP 2 LAST PATH I28
J 0
(-375 3300);
DISPLAY 1.021277 (-375 3300);
PAINT ORANGE (-375 3300);
DISPLAY INVISIBLE (-375 3300);
FORCEPROP 2 LAST CDS_LIB mstr_standard
J 0
(-550 3225);
PAINT ORANGE (-550 3225);
DISPLAY INVISIBLE (-550 3225);
FORCEADD P3V3_STBY..1
(-3400 3250);
FORCEPROP 3 LASTPIN (-3400 3200) SIG_NAME P3V3_STBY\g
J 0
(-3390 3210);
DISPLAY 0.659574 (-3390 3210);
PAINT MONO (-3390 3210);
DISPLAY INVISIBLE (-3390 3210);
FORCEPROP 1 LAST HDL_POWER P3V3_STBY
J 0
(-3700 3125);
DISPLAY 0.872340 (-3700 3125);
PAINT ORANGE (-3700 3125);
DISPLAY INVISIBLE (-3700 3125);
FORCEPROP 1 LAST BODY_TYPE PLUMBING
J 0
(-3445 3207);
DISPLAY 0.340426 (-3445 3207);
PAINT GREEN (-3445 3207);
DISPLAY INVISIBLE (-3445 3207);
FORCEPROP 1 LAST VOLTAGE 3.3V
J 0
(-3445 3207);
DISPLAY 0.340426 (-3445 3207);
PAINT SKYBLUE (-3445 3207);
DISPLAY INVISIBLE (-3445 3207);
FORCEPROP 2 LAST CDS_LIB mstr_symbols
J 0
(-3400 3250);
PAINT ORANGE (-3400 3250);
DISPLAY INVISIBLE (-3400 3250);
FORCEPROP 1 LAST SIZE 1B
J 0
(-3355 3272);
DISPLAY 0.340426 (-3355 3272);
PAINT GREEN (-3355 3272);
DISPLAY INVISIBLE (-3355 3272);
FORCEPROP 1 LAST PATH I29
J 0
(-3355 3252);
DISPLAY 0.340426 (-3355 3252);
PAINT GREEN (-3355 3252);
DISPLAY INVISIBLE (-3355 3252);
FORCEADD DIODE..1
(-5675 2750);
FORCEPROP 1 LASTPIN (-5775 2750) $PN 2
J 2
(-5740 2760);
DISPLAY 0.617021 (-5740 2760);
PAINT AQUA (-5740 2760);
FORCEPROP 1 LAST PART_NUMBER D89194-001
J 0
(-5700 2850);
DISPLAY 0.617021 (-5700 2850);
PAINT BLUE (-5700 2850);
FORCEPROP 1 LAST MATERIAL IC
J 0
(-5700 2572);
DISPLAY 0.617021 (-5700 2572);
PAINT SKYBLUE (-5700 2572);
FORCEPROP 1 LAST LOCATION CR1L2
J 0
(-5702 2906);
DISPLAY 0.617021 (-5702 2906);
PAINT AQUA (-5702 2906);
FORCEPROP 1 LAST PACK_TYPE SM
J 0
(-5700 2510);
DISPLAY 0.617021 (-5700 2510);
PAINT SKYBLUE (-5700 2510);
FORCEPROP 1 LASTPIN (-5575 2750) $PN 1
J 0
(-5610 2760);
DISPLAY 0.617021 (-5610 2760);
PAINT AQUA (-5610 2760);
FORCEPROP 1 LAST VALUE 1N4148W
J 0
(-5700 2625);
DISPLAY 0.617021 (-5700 2625);
PAINT SKYBLUE (-5700 2625);
FORCEPROP 2 LAST ROOM UART_MUX
J 0
(-5700 2950);
DISPLAY 1.021277 (-5700 2950);
PAINT ORANGE (-5700 2950);
DISPLAY INVISIBLE (-5700 2950);
FORCEPROP 1 LAST PATH I3
J 0
(-5695 2960);
DISPLAY 0.978723 (-5695 2960);
PAINT PINK (-5695 2960);
DISPLAY INVISIBLE (-5695 2960);
FORCEPROP 2 LAST CDS_LOCATION CR1L2
J 0
(-5702 2906);
DISPLAY 0.617021 (-5702 2906);
PAINT AQUA (-5702 2906);
DISPLAY INVISIBLE (-5702 2906);
FORCEPROP 2 LAST SEC 1
J 0
(-5675 3025);
DISPLAY 0.680851 (-5675 3025);
PAINT MONO (-5675 3025);
DISPLAY INVISIBLE (-5675 3025);
FORCEPROP 2 LAST BOM_COST DEBUG
J 0
(-5700 3000);
DISPLAY 1.021277 (-5700 3000);
PAINT ORANGE (-5700 3000);
DISPLAY INVISIBLE (-5700 3000);
FORCEPROP 2 LAST CDS_LIB mstr_discrete
J 0
(-5675 2750);
PAINT ORANGE (-5675 2750);
DISPLAY INVISIBLE (-5675 2750);
FORCEPROP 2 LAST SEC_TYPE SM
J 0
(-5675 3025);
DISPLAY 1.021277 (-5675 3025);
PAINT ORANGE (-5675 3025);
DISPLAY INVISIBLE (-5675 3025);
FORCEADD OFFPAGE..2
(-3125 1800);
FORCEPROP 2 LAST $XR2 190 
J 0
(-2696 1800);
DISPLAY 0.638298 (-2696 1800);
PAINT MONO (-2696 1800);
FORCEPROP 2 LAST $XR1 145 
J 0
(-2816 1800);
DISPLAY 0.638298 (-2816 1800);
PAINT MONO (-2816 1800);
FORCEPROP 2 LAST $XR0 120 
J 0
(-2936 1800);
DISPLAY 0.638298 (-2936 1800);
PAINT MONO (-2936 1800);
FORCEPROP 1 LAST COMMENT_BODY TRUE
J 0
(-3170 1705);
DISPLAY 0.872340 (-3170 1705);
PAINT GREEN (-3170 1705);
DISPLAY INVISIBLE (-3170 1705);
FORCEPROP 1 LAST OFFPAGE TRUE
J 0
(-2800 1675);
DISPLAY 0.872340 (-2800 1675);
PAINT GREEN (-2800 1675);
DISPLAY INVISIBLE (-2800 1675);
FORCEPROP 2 LAST PATH I31
J 0
(-2675 1850);
DISPLAY 1.021277 (-2675 1850);
PAINT ORANGE (-2675 1850);
DISPLAY INVISIBLE (-2675 1850);
FORCEPROP 2 LAST CDS_LIB mstr_standard
J 0
(-3125 1800);
PAINT ORANGE (-3125 1800);
DISPLAY INVISIBLE (-3125 1800);
FORCEADD GND..1
(-3950 975);
FORCEPROP 3 LASTPIN (-3950 1025) SIG_NAME GND\g
J 0
(-3940 1035);
DISPLAY 0.659574 (-3940 1035);
PAINT MONO (-3940 1035);
DISPLAY INVISIBLE (-3940 1035);
FORCEPROP 1 LAST HDL_POWER GND
J 0
(-3950 1125);
DISPLAY 0.872340 (-3950 1125);
PAINT GREEN (-3950 1125);
DISPLAY INVISIBLE (-3950 1125);
FORCEPROP 1 LAST BODY_TYPE PLUMBING
J 0
(-3995 932);
DISPLAY 0.340426 (-3995 932);
PAINT GREEN (-3995 932);
DISPLAY INVISIBLE (-3995 932);
FORCEPROP 1 LAST SIZE 1B
J 0
(-3875 925);
DISPLAY 0.872340 (-3875 925);
PAINT AQUA (-3875 925);
DISPLAY INVISIBLE (-3875 925);
FORCEPROP 2 LAST CDS_LIB mstr_symbols
J 0
(-3950 975);
PAINT ORANGE (-3950 975);
DISPLAY INVISIBLE (-3950 975);
FORCEPROP 1 LAST VOLTAGE 0.0V
J 0
(-3995 932);
DISPLAY 0.340426 (-3995 932);
PAINT SKYBLUE (-3995 932);
DISPLAY INVISIBLE (-3995 932);
FORCEPROP 1 LAST PATH I36
J 0
(-3875 975);
DISPLAY 0.872340 (-3875 975);
PAINT AQUA (-3875 975);
DISPLAY INVISIBLE (-3875 975);
FORCEADD P3V3_STBY..1
(-3950 2375);
FORCEPROP 3 LASTPIN (-3950 2325) SIG_NAME P3V3_STBY\g
J 0
(-3940 2335);
DISPLAY 0.659574 (-3940 2335);
PAINT MONO (-3940 2335);
DISPLAY INVISIBLE (-3940 2335);
FORCEPROP 1 LAST HDL_POWER P3V3_STBY
J 0
(-4250 2250);
DISPLAY 0.872340 (-4250 2250);
PAINT ORANGE (-4250 2250);
DISPLAY INVISIBLE (-4250 2250);
FORCEPROP 1 LAST BODY_TYPE PLUMBING
J 0
(-3995 2332);
DISPLAY 0.340426 (-3995 2332);
PAINT GREEN (-3995 2332);
DISPLAY INVISIBLE (-3995 2332);
FORCEPROP 1 LAST SIZE 1B
J 0
(-3905 2397);
DISPLAY 0.340426 (-3905 2397);
PAINT GREEN (-3905 2397);
DISPLAY INVISIBLE (-3905 2397);
FORCEPROP 2 LAST CDS_LIB mstr_symbols
J 0
(-3950 2375);
PAINT ORANGE (-3950 2375);
DISPLAY INVISIBLE (-3950 2375);
FORCEPROP 1 LAST VOLTAGE 3.3V
J 0
(-3995 2332);
DISPLAY 0.340426 (-3995 2332);
PAINT SKYBLUE (-3995 2332);
DISPLAY INVISIBLE (-3995 2332);
FORCEPROP 1 LAST PATH I38
J 0
(-3905 2377);
DISPLAY 0.340426 (-3905 2377);
PAINT GREEN (-3905 2377);
DISPLAY INVISIBLE (-3905 2377);
FORCEADD DIODE..1
(-4975 2750);
FORCEPROP 1 LAST VALUE 1N4148W
J 0
(-5000 2625);
DISPLAY 0.617021 (-5000 2625);
PAINT SKYBLUE (-5000 2625);
FORCEPROP 1 LAST PACK_TYPE SM
J 0
(-5000 2510);
DISPLAY 0.617021 (-5000 2510);
PAINT SKYBLUE (-5000 2510);
FORCEPROP 1 LASTPIN (-4875 2750) $PN 1
J 0
(-4910 2760);
DISPLAY 0.617021 (-4910 2760);
PAINT AQUA (-4910 2760);
FORCEPROP 1 LASTPIN (-5075 2750) $PN 2
J 2
(-5040 2760);
DISPLAY 0.617021 (-5040 2760);
PAINT AQUA (-5040 2760);
FORCEPROP 1 LAST PART_NUMBER D89194-001
J 0
(-5000 2850);
DISPLAY 0.617021 (-5000 2850);
PAINT BLUE (-5000 2850);
FORCEPROP 1 LAST LOCATION CR1L3
J 0
(-5002 2906);
DISPLAY 0.617021 (-5002 2906);
PAINT AQUA (-5002 2906);
FORCEPROP 1 LAST MATERIAL IC
J 0
(-5000 2572);
DISPLAY 0.617021 (-5000 2572);
PAINT SKYBLUE (-5000 2572);
FORCEPROP 2 LAST ROOM UART_MUX
J 0
(-5000 2950);
DISPLAY 1.021277 (-5000 2950);
PAINT ORANGE (-5000 2950);
DISPLAY INVISIBLE (-5000 2950);
FORCEPROP 1 LAST PATH I4
J 0
(-4995 2960);
DISPLAY 0.978723 (-4995 2960);
PAINT PINK (-4995 2960);
DISPLAY INVISIBLE (-4995 2960);
FORCEPROP 2 LAST CDS_LOCATION CR1L3
J 0
(-5002 2906);
DISPLAY 0.617021 (-5002 2906);
PAINT AQUA (-5002 2906);
DISPLAY INVISIBLE (-5002 2906);
FORCEPROP 2 LAST SEC 1
J 0
(-4975 3025);
DISPLAY 0.680851 (-4975 3025);
PAINT MONO (-4975 3025);
DISPLAY INVISIBLE (-4975 3025);
FORCEPROP 2 LAST BOM_COST DEBUG
J 0
(-5000 3000);
DISPLAY 1.021277 (-5000 3000);
PAINT ORANGE (-5000 3000);
DISPLAY INVISIBLE (-5000 3000);
FORCEPROP 2 LAST CDS_LIB mstr_discrete
J 0
(-4975 2750);
PAINT ORANGE (-4975 2750);
DISPLAY INVISIBLE (-4975 2750);
FORCEPROP 2 LAST SEC_TYPE SM
J 0
(-4975 3025);
DISPLAY 1.021277 (-4975 3025);
PAINT ORANGE (-4975 3025);
DISPLAY INVISIBLE (-4975 3025);
FORCEADD FET_N..8
(-1450 2650);
FORCEPROP 1 LAST MATERIAL FET
J 0
(-1250 2550);
DISPLAY 0.617021 (-1250 2550);
PAINT SKYBLUE (-1250 2550);
FORCEPROP 1 LAST PART_NUMBER C79254-001
J 0
(-1250 2450);
DISPLAY 0.617021 (-1250 2450);
PAINT BLUE (-1250 2450);
FORCEPROP 1 LASTPIN (-1650 2550) $PN 1
J 2
(-1647 2565);
DISPLAY 0.617021 (-1647 2565);
PAINT WHITE (-1647 2565);
FORCEPROP 1 LASTPIN (-1450 2850) $PN 3
J 2
(-1397 2815);
DISPLAY 0.617021 (-1397 2815);
PAINT WHITE (-1397 2815);
FORCEPROP 1 LAST LOCATION Q6W4
J 0
(-1250 2650);
DISPLAY 0.617021 (-1250 2650);
PAINT AQUA (-1250 2650);
FORCEPROP 1 LASTPIN (-1450 2450) $PN 2
J 2
(-1392 2450);
DISPLAY 0.617021 (-1392 2450);
PAINT WHITE (-1392 2450);
FORCEPROP 1 LAST VALUE 2N7002
J 0
(-1250 2600);
DISPLAY 0.617021 (-1250 2600);
PAINT SKYBLUE (-1250 2600);
FORCEPROP 2 LAST CDS_LOCATION Q6W4
J 0
(-1250 2650);
DISPLAY 0.617021 (-1250 2650);
PAINT AQUA (-1250 2650);
DISPLAY INVISIBLE (-1250 2650);
FORCEPROP 1 LAST PATH I43
J 0
(-1250 2700);
DISPLAY 0.978723 (-1250 2700);
PAINT BLUE (-1250 2700);
DISPLAY INVISIBLE (-1250 2700);
FORCEPROP 1 LAST PACK_TYPE SOT23LF
J 0
(-1250 2500);
DISPLAY 0.978723 (-1250 2500);
PAINT SKYBLUE (-1250 2500);
DISPLAY INVISIBLE (-1250 2500);
FORCEPROP 0 LAST ROOM HOT_SWAP
J 0
(-1250 2750);
DISPLAY 1.021277 (-1250 2750);
PAINT ORANGE (-1250 2750);
DISPLAY INVISIBLE (-1250 2750);
FORCEPROP 2 LAST SEC_TYPE SOT23LF
J 0
(-1250 2750);
DISPLAY 1.021277 (-1250 2750);
PAINT ORANGE (-1250 2750);
DISPLAY INVISIBLE (-1250 2750);
FORCEPROP 2 LAST SEC 1
J 0
(-1250 2750);
DISPLAY 0.680851 (-1250 2750);
PAINT MONO (-1250 2750);
DISPLAY INVISIBLE (-1250 2750);
FORCEPROP 2 LAST CDS_LIB mstr_discrete
J 0
(-1450 2650);
PAINT ORANGE (-1450 2650);
DISPLAY INVISIBLE (-1450 2650);
FORCEPROP 0 LAST CDS_SEC 1
J 0
(-1250 2700);
PAINT MONO (-1250 2700);
DISPLAY INVISIBLE (-1250 2700);
FORCEADD GND..1
(-1450 2350);
FORCEPROP 3 LASTPIN (-1450 2400) SIG_NAME GND\g
J 0
(-1440 2410);
DISPLAY 0.659574 (-1440 2410);
PAINT MONO (-1440 2410);
DISPLAY INVISIBLE (-1440 2410);
FORCEPROP 1 LAST HDL_POWER GND
J 0
(-1450 2500);
DISPLAY 0.872340 (-1450 2500);
PAINT GREEN (-1450 2500);
DISPLAY INVISIBLE (-1450 2500);
FORCEPROP 1 LAST BODY_TYPE PLUMBING
J 0
(-1495 2307);
DISPLAY 0.340426 (-1495 2307);
PAINT GREEN (-1495 2307);
DISPLAY INVISIBLE (-1495 2307);
FORCEPROP 1 LAST VOLTAGE 0.0V
J 0
(-1495 2307);
DISPLAY 0.340426 (-1495 2307);
PAINT SKYBLUE (-1495 2307);
DISPLAY INVISIBLE (-1495 2307);
FORCEPROP 2 LAST CDS_LIB mstr_symbols
J 0
(-1450 2350);
PAINT ORANGE (-1450 2350);
DISPLAY INVISIBLE (-1450 2350);
FORCEPROP 1 LAST SIZE 1B
J 0
(-1375 2300);
DISPLAY 0.872340 (-1375 2300);
PAINT AQUA (-1375 2300);
DISPLAY INVISIBLE (-1375 2300);
FORCEPROP 1 LAST PATH I44
J 0
(-1375 2350);
DISPLAY 0.872340 (-1375 2350);
PAINT AQUA (-1375 2350);
DISPLAY INVISIBLE (-1375 2350);
FORCEADD OFFPAGE..1
(-2475 2550);
FORCEPROP 2 LAST $XR0 176 
J 0
(-2757 2550);
DISPLAY 0.638298 (-2757 2550);
PAINT MONO (-2757 2550);
FORCEPROP 1 LAST COMMENT_BODY TRUE
J 0
(-2350 2450);
DISPLAY 0.872340 (-2350 2450);
PAINT GREEN (-2350 2450);
DISPLAY INVISIBLE (-2350 2450);
FORCEPROP 1 LAST OFFPAGE TRUE
J 0
(-2150 2425);
DISPLAY 0.872340 (-2150 2425);
PAINT GREEN (-2150 2425);
DISPLAY INVISIBLE (-2150 2425);
FORCEPROP 2 LAST CDS_LIB mstr_standard
J 0
(-2475 2550);
PAINT ORANGE (-2475 2550);
DISPLAY INVISIBLE (-2475 2550);
FORCEPROP 2 LAST PATH I45
J 0
(-2725 2600);
DISPLAY 1.021277 (-2725 2600);
PAINT ORANGE (-2725 2600);
DISPLAY INVISIBLE (-2725 2600);
FORCEADD RES..2
(-3950 2100);
FORCEPROP 1 LAST MATERIAL CHIP
J 0
(-3910 2025);
DISPLAY 0.617021 (-3910 2025);
PAINT SKYBLUE (-3910 2025);
FORCEPROP 1 LAST TOLERANCE 1%
J 0
(-3905 2125);
DISPLAY 0.617021 (-3905 2125);
PAINT SKYBLUE (-3905 2125);
FORCEPROP 1 LAST VALUE 1.00K
J 0
(-3905 2175);
DISPLAY 0.617021 (-3905 2175);
PAINT SKYBLUE (-3905 2175);
FORCEPROP 1 LASTPIN (-3950 2000) $PN 2
J 0
(-3945 2010);
DISPLAY 0.617021 (-3945 2010);
PAINT ORANGE (-3945 2010);
FORCEPROP 1 LASTPIN (-3950 2200) $PN 1
J 0
(-3945 2162);
DISPLAY 0.617021 (-3945 2162);
PAINT ORANGE (-3945 2162);
FORCEPROP 1 LAST WATTAGE 1/16W
J 0
(-3910 2075);
DISPLAY 0.617021 (-3910 2075);
PAINT SKYBLUE (-3910 2075);
FORCEPROP 1 LAST LOCATION R6W16
J 0
(-3905 2225);
DISPLAY 0.617021 (-3905 2225);
PAINT AQUA (-3905 2225);
FORCEPROP 1 LAST PACK_TYPE 0402
J 0
(-3910 1925);
DISPLAY 0.617021 (-3910 1925);
PAINT SKYBLUE (-3910 1925);
FORCEPROP 1 LAST PART_NUMBER G21796-026
J 0
(-3910 1975);
DISPLAY 0.617021 (-3910 1975);
PAINT BLUE (-3910 1975);
FORCEPROP 1 LAST PATH I46
J 0
(-3900 2275);
DISPLAY 0.978723 (-3900 2275);
PAINT WHITE (-3900 2275);
DISPLAY INVISIBLE (-3900 2275);
FORCEPROP 2 LAST SEC_TYPE 0402
J 0
(-3900 2325);
DISPLAY 1.021277 (-3900 2325);
PAINT ORANGE (-3900 2325);
DISPLAY INVISIBLE (-3900 2325);
FORCEPROP 2 LAST CDS_LIB mstr_discrete
J 0
(-3950 2100);
PAINT ORANGE (-3950 2100);
DISPLAY INVISIBLE (-3950 2100);
FORCEPROP 2 LAST BOM_COST DEBUG
J 0
(-3900 2325);
DISPLAY 1.021277 (-3900 2325);
PAINT ORANGE (-3900 2325);
DISPLAY INVISIBLE (-3900 2325);
FORCEPROP 2 LAST SEC 1
J 0
(-3900 2325);
DISPLAY 0.680851 (-3900 2325);
PAINT MONO (-3900 2325);
DISPLAY INVISIBLE (-3900 2325);
FORCEPROP 2 LAST ROOM UART_MUX
J 0
(-3900 2275);
DISPLAY 1.021277 (-3900 2275);
PAINT ORANGE (-3900 2275);
DISPLAY INVISIBLE (-3900 2275);
FORCEPROP 2 LAST CDS_LOCATION R6W16
J 0
(-3905 2225);
DISPLAY 0.617021 (-3905 2225);
PAINT AQUA (-3905 2225);
DISPLAY INVISIBLE (-3905 2225);
FORCEADD NPN..1
(-4000 1450);
FORCEPROP 1 LAST VALUE MMBT3904
J 0
(-3850 1450);
DISPLAY 0.617021 (-3850 1450);
PAINT SKYBLUE (-3850 1450);
FORCEPROP 1 LASTPIN (-4100 1450) $PN 1
J 0
(-4155 1475);
DISPLAY 0.617021 (-4155 1475);
PAINT GREEN (-4155 1475);
FORCEPROP 1 LAST PART_NUMBER C52245-001
J 0
(-3850 1300);
DISPLAY 0.617021 (-3850 1300);
PAINT BLUE (-3850 1300);
FORCEPROP 1 LASTPIN (-3950 1350) $PN 2
J 0
(-3925 1300);
DISPLAY 0.617021 (-3925 1300);
PAINT GREEN (-3925 1300);
FORCEPROP 1 LAST PACK_TYPE SM
J 0
(-3850 1350);
DISPLAY 0.617021 (-3850 1350);
PAINT SKYBLUE (-3850 1350);
FORCEPROP 1 LAST MATERIAL IC
J 0
(-3850 1400);
DISPLAY 0.617021 (-3850 1400);
PAINT SKYBLUE (-3850 1400);
FORCEPROP 1 LASTPIN (-3950 1550) $PN 3
J 0
(-3931 1560);
DISPLAY 0.617021 (-3931 1560);
PAINT GREEN (-3931 1560);
FORCEPROP 1 LAST LOCATION Q6W2
J 0
(-3850 1500);
DISPLAY 0.617021 (-3850 1500);
PAINT AQUA (-3850 1500);
FORCEPROP 2 LAST ROOM UART_MUX
J 0
(-3850 1550);
DISPLAY 1.021277 (-3850 1550);
PAINT ORANGE (-3850 1550);
DISPLAY INVISIBLE (-3850 1550);
FORCEPROP 2 LAST SEC 1
J 0
(-3850 1600);
DISPLAY 0.680851 (-3850 1600);
PAINT MONO (-3850 1600);
DISPLAY INVISIBLE (-3850 1600);
FORCEPROP 2 LAST BOM_COST DEBUG
J 0
(-3850 1600);
DISPLAY 1.021277 (-3850 1600);
PAINT ORANGE (-3850 1600);
DISPLAY INVISIBLE (-3850 1600);
FORCEPROP 2 LAST CDS_LIB mstr_discrete
J 0
(-4000 1450);
PAINT ORANGE (-4000 1450);
DISPLAY INVISIBLE (-4000 1450);
FORCEPROP 2 LAST SEC_TYPE SM
J 0
(-3850 1600);
DISPLAY 1.021277 (-3850 1600);
PAINT ORANGE (-3850 1600);
DISPLAY INVISIBLE (-3850 1600);
FORCEPROP 1 LAST PATH I47
J 0
(-3850 1550);
DISPLAY 0.978723 (-3850 1550);
PAINT BLUE (-3850 1550);
DISPLAY INVISIBLE (-3850 1550);
FORCEPROP 2 LAST CDS_LOCATION Q6W2
J 0
(-3850 1500);
DISPLAY 0.617021 (-3850 1500);
PAINT AQUA (-3850 1500);
DISPLAY INVISIBLE (-3850 1500);
FORCEADD RES..2
R 1
(-5950 1450);
FORCEPROP 1 LAST LOCATION R6W49
J 0
(-6000 1395);
DISPLAY 0.617021 (-6000 1395);
PAINT AQUA (-6000 1395);
FORCEPROP 1 LASTPIN (-5850 1450) $PN 2
J 0
(-5885 1455);
DISPLAY 0.617021 (-5885 1455);
PAINT ORANGE (-5885 1455);
FORCEPROP 1 LAST PART_NUMBER G21796-133
J 0
(-6000 1140);
DISPLAY 0.617021 (-6000 1140);
PAINT BLUE (-6000 1140);
FORCEPROP 1 LAST TOLERANCE 1%
J 0
(-6000 1295);
DISPLAY 0.617021 (-6000 1295);
PAINT SKYBLUE (-6000 1295);
FORCEPROP 1 LAST VALUE 40.2K
J 0
(-6000 1345);
DISPLAY 0.617021 (-6000 1345);
PAINT SKYBLUE (-6000 1345);
FORCEPROP 1 LAST PACK_TYPE 0402
J 0
(-6000 1090);
DISPLAY 0.617021 (-6000 1090);
PAINT SKYBLUE (-6000 1090);
FORCEPROP 1 LAST MATERIAL CHIP
J 0
(-6000 1190);
DISPLAY 0.617021 (-6000 1190);
PAINT SKYBLUE (-6000 1190);
FORCEPROP 1 LAST WATTAGE 1/16W
J 0
(-6000 1240);
DISPLAY 0.617021 (-6000 1240);
PAINT SKYBLUE (-6000 1240);
FORCEPROP 1 LASTPIN (-6050 1450) $PN 1
J 0
(-6037 1455);
DISPLAY 0.617021 (-6037 1455);
PAINT ORANGE (-6037 1455);
FORCEPROP 2 LAST SEC_TYPE 0402
R 1
J 0
(-6175 1500);
DISPLAY 1.021277 (-6175 1500);
PAINT ORANGE (-6175 1500);
DISPLAY INVISIBLE (-6175 1500);
FORCEPROP 2 LAST SEC 1
R 1
J 0
(-6175 1500);
DISPLAY 0.680851 (-6175 1500);
PAINT MONO (-6175 1500);
DISPLAY INVISIBLE (-6175 1500);
FORCEPROP 0 LAST ROOM HOT_SWAP
R 1
J 0
(-6125 1500);
DISPLAY 1.021277 (-6125 1500);
PAINT ORANGE (-6125 1500);
DISPLAY INVISIBLE (-6125 1500);
FORCEPROP 2 LAST CDS_LIB mstr_discrete
R 1
J 0
(-5950 1450);
PAINT ORANGE (-5950 1450);
DISPLAY INVISIBLE (-5950 1450);
FORCEPROP 1 LAST PATH I48
R 1
J 0
(-6125 1500);
DISPLAY 0.978723 (-6125 1500);
PAINT WHITE (-6125 1500);
DISPLAY INVISIBLE (-6125 1500);
FORCEPROP 2 LAST CDS_LOCATION R6W49
R 1
J 0
(-6075 1495);
DISPLAY 0.617021 (-6075 1495);
PAINT AQUA (-6075 1495);
DISPLAY INVISIBLE (-6075 1495);
FORCEADD DIODE..1
(-4225 2750);
FORCEPROP 1 LASTPIN (-4325 2750) $PN 2
J 2
(-4290 2760);
DISPLAY 0.617021 (-4290 2760);
PAINT AQUA (-4290 2760);
FORCEPROP 1 LAST PART_NUMBER D89194-001
J 0
(-4250 2850);
DISPLAY 0.617021 (-4250 2850);
PAINT BLUE (-4250 2850);
FORCEPROP 1 LASTPIN (-4125 2750) $PN 1
J 0
(-4160 2760);
DISPLAY 0.617021 (-4160 2760);
PAINT AQUA (-4160 2760);
FORCEPROP 1 LAST LOCATION CR1L4
J 0
(-4252 2906);
DISPLAY 0.617021 (-4252 2906);
PAINT AQUA (-4252 2906);
FORCEPROP 1 LAST VALUE 1N4148W
J 0
(-4250 2625);
DISPLAY 0.617021 (-4250 2625);
PAINT SKYBLUE (-4250 2625);
FORCEPROP 1 LAST PACK_TYPE SM
J 0
(-4250 2510);
DISPLAY 0.617021 (-4250 2510);
PAINT SKYBLUE (-4250 2510);
FORCEPROP 1 LAST MATERIAL IC
J 0
(-4250 2572);
DISPLAY 0.617021 (-4250 2572);
PAINT SKYBLUE (-4250 2572);
FORCEPROP 2 LAST SEC_TYPE SM
J 0
(-4225 3025);
DISPLAY 1.021277 (-4225 3025);
PAINT ORANGE (-4225 3025);
DISPLAY INVISIBLE (-4225 3025);
FORCEPROP 2 LAST CDS_LIB mstr_discrete
J 0
(-4225 2750);
PAINT ORANGE (-4225 2750);
DISPLAY INVISIBLE (-4225 2750);
FORCEPROP 2 LAST BOM_COST DEBUG
J 0
(-4250 3000);
DISPLAY 1.021277 (-4250 3000);
PAINT ORANGE (-4250 3000);
DISPLAY INVISIBLE (-4250 3000);
FORCEPROP 2 LAST SEC 1
J 0
(-4225 3025);
DISPLAY 0.680851 (-4225 3025);
PAINT MONO (-4225 3025);
DISPLAY INVISIBLE (-4225 3025);
FORCEPROP 2 LAST CDS_LOCATION CR1L4
J 0
(-4252 2906);
DISPLAY 0.617021 (-4252 2906);
PAINT AQUA (-4252 2906);
DISPLAY INVISIBLE (-4252 2906);
FORCEPROP 2 LAST ROOM UART_MUX
J 0
(-4250 2950);
DISPLAY 1.021277 (-4250 2950);
PAINT ORANGE (-4250 2950);
DISPLAY INVISIBLE (-4250 2950);
FORCEPROP 1 LAST PATH I5
J 0
(-4245 2960);
DISPLAY 0.978723 (-4245 2960);
PAINT PINK (-4245 2960);
DISPLAY INVISIBLE (-4245 2960);
FORCEADD RES..1
(-6975 2750);
FORCEPROP 1 LAST PACK_TYPE 0402
J 0
(-7025 2550);
DISPLAY 0.617021 (-7025 2550);
PAINT SKYBLUE (-7025 2550);
FORCEPROP 1 LASTPIN (-7075 2750) $PN 1
J 0
(-7063 2762);
DISPLAY 0.617021 (-7063 2762);
PAINT ORANGE (-7063 2762);
FORCEPROP 1 LASTPIN (-6875 2750) $PN 2
J 0
(-6913 2762);
DISPLAY 0.617021 (-6913 2762);
PAINT ORANGE (-6913 2762);
FORCEPROP 1 LAST TOLERANCE 5%
J 0
(-6975 2650);
DISPLAY 0.617021 (-6975 2650);
PAINT SKYBLUE (-6975 2650);
FORCEPROP 1 LAST VALUE 0.0
J 2
(-7000 2650);
DISPLAY 0.617021 (-7000 2650);
PAINT SKYBLUE (-7000 2650);
FORCEPROP 1 LAST PART_NUMBER G21497-005
J 0
(-7025 2850);
DISPLAY 0.617021 (-7025 2850);
PAINT BLUE (-7025 2850);
FORCEPROP 1 LAST LOCATION R1L6
J 0
(-7025 2800);
DISPLAY 0.617021 (-7025 2800);
PAINT AQUA (-7025 2800);
FORCEPROP 1 LAST MATERIAL CHIP
J 0
(-6975 2600);
DISPLAY 0.617021 (-6975 2600);
PAINT SKYBLUE (-6975 2600);
FORCEPROP 1 LAST WATTAGE 1/16W
J 2
(-7000 2600);
DISPLAY 0.617021 (-7000 2600);
PAINT SKYBLUE (-7000 2600);
FORCEPROP 2 LAST ROOM UART_MUX
J 0
(-7025 2900);
DISPLAY 1.021277 (-7025 2900);
PAINT ORANGE (-7025 2900);
DISPLAY INVISIBLE (-7025 2900);
FORCEPROP 1 LAST PATH I6
J 0
(-7025 2900);
DISPLAY 0.978723 (-7025 2900);
PAINT WHITE (-7025 2900);
DISPLAY INVISIBLE (-7025 2900);
FORCEPROP 2 LAST CDS_LOCATION R1L6
J 0
(-7025 2800);
DISPLAY 0.617021 (-7025 2800);
PAINT AQUA (-7025 2800);
DISPLAY INVISIBLE (-7025 2800);
FORCEPROP 2 LAST SEC 1
J 0
(-7025 2950);
DISPLAY 0.680851 (-7025 2950);
PAINT MONO (-7025 2950);
DISPLAY INVISIBLE (-7025 2950);
FORCEPROP 2 LAST BOM_COST DEBUG
J 0
(-7025 2950);
DISPLAY 1.021277 (-7025 2950);
PAINT ORANGE (-7025 2950);
DISPLAY INVISIBLE (-7025 2950);
FORCEPROP 2 LAST CDS_LIB mstr_discrete
J 0
(-6975 2750);
PAINT ORANGE (-6975 2750);
DISPLAY INVISIBLE (-6975 2750);
FORCEPROP 2 LAST SEC_TYPE 0402
J 0
(-7025 2950);
DISPLAY 1.021277 (-7025 2950);
PAINT ORANGE (-7025 2950);
DISPLAY INVISIBLE (-7025 2950);
FORCEADD NPN..1
(-3450 2750);
FORCEPROP 1 LASTPIN (-3550 2750) $PN 1
J 0
(-3605 2775);
DISPLAY 0.617021 (-3605 2775);
PAINT GREEN (-3605 2775);
FORCEPROP 1 LASTPIN (-3400 2850) $PN 3
J 0
(-3381 2860);
DISPLAY 0.617021 (-3381 2860);
PAINT GREEN (-3381 2860);
FORCEPROP 1 LAST PART_NUMBER C52245-001
J 0
(-3300 2600);
DISPLAY 0.617021 (-3300 2600);
PAINT BLUE (-3300 2600);
FORCEPROP 1 LASTPIN (-3400 2650) $PN 2
J 0
(-3375 2600);
DISPLAY 0.617021 (-3375 2600);
PAINT GREEN (-3375 2600);
FORCEPROP 1 LAST PACK_TYPE SM
J 0
(-3300 2650);
DISPLAY 0.617021 (-3300 2650);
PAINT SKYBLUE (-3300 2650);
FORCEPROP 1 LAST LOCATION Q1L3
J 0
(-3300 2800);
DISPLAY 0.617021 (-3300 2800);
PAINT AQUA (-3300 2800);
FORCEPROP 1 LAST VALUE MMBT3904
J 0
(-3300 2750);
DISPLAY 0.617021 (-3300 2750);
PAINT SKYBLUE (-3300 2750);
FORCEPROP 1 LAST MATERIAL IC
J 0
(-3300 2700);
DISPLAY 0.617021 (-3300 2700);
PAINT SKYBLUE (-3300 2700);
FORCEPROP 1 LAST PATH I8
J 0
(-3300 2850);
DISPLAY 0.978723 (-3300 2850);
PAINT BLUE (-3300 2850);
DISPLAY INVISIBLE (-3300 2850);
FORCEPROP 2 LAST ROOM UART_MUX
J 0
(-3300 2850);
DISPLAY 1.021277 (-3300 2850);
PAINT ORANGE (-3300 2850);
DISPLAY INVISIBLE (-3300 2850);
FORCEPROP 2 LAST CDS_LOCATION Q1L3
J 0
(-3300 2800);
DISPLAY 0.617021 (-3300 2800);
PAINT AQUA (-3300 2800);
DISPLAY INVISIBLE (-3300 2800);
FORCEPROP 2 LAST SEC 1
J 0
(-3300 2900);
DISPLAY 0.680851 (-3300 2900);
PAINT MONO (-3300 2900);
DISPLAY INVISIBLE (-3300 2900);
FORCEPROP 2 LAST BOM_COST DEBUG
J 0
(-3300 2900);
DISPLAY 1.021277 (-3300 2900);
PAINT ORANGE (-3300 2900);
DISPLAY INVISIBLE (-3300 2900);
FORCEPROP 2 LAST CDS_LIB mstr_discrete
J 0
(-3450 2750);
PAINT ORANGE (-3450 2750);
DISPLAY INVISIBLE (-3450 2750);
FORCEPROP 2 LAST SEC_TYPE SM
J 0
(-3300 2900);
DISPLAY 1.021277 (-3300 2900);
PAINT ORANGE (-3300 2900);
DISPLAY INVISIBLE (-3300 2900);
FORCEADD INTEL_CORP_BPAGE..1
(0 0);
FORCEPROP 1 LAST CDS_CON_LAST_MODIFIED Fri Jun 16 17:49:02 2017
J 0
(-1425 325);
DISPLAY 1.361702 (-1425 325);
PAINT GREEN (-1425 325);
DISPLAY INVISIBLE (-1425 325);
FORCEPROP 1 LAST CUSTOM_TXT_CDS <CURRENT_DESIGN_SHEET> OF <TOTAL_DESIGN_SHEETS>
J 0
(-500 25);
PAINT ORANGE (-500 25);
FORCEPROP 1 LAST CUSTOM_TXT_CDS <CON_LAST_MODIFIED>
J 0
(-4000 100);
PAINT ORANGE (-4000 100);
FORCEPROP 2 LAST CUSTOM_TXT_CDS <XR_PAGE_TITLE>
J 0
(-7890 5250);
DISPLAY 0.638298 (-7890 5250);
PAINT PINK (-7890 5250);
DISPLAY INVISIBLE (-7890 5250);
FORCEPROP 1 LAST SCH_TITLE UART MUX CONTROL
J 0
(-7950 50);
DISPLAY 1.212766 (-7950 50);
PAINT ORANGE (-7950 50);
FORCEPROP 1 LAST COMMENT_BODY TRUE
J 0
(12 12);
DISPLAY 0.617021 (12 12);
PAINT GREEN (12 12);
DISPLAY INVISIBLE (12 12);
FORCEPROP 2 LAST PAGE_BORDER TRUE
J 0
(-7890 5250);
DISPLAY 0.851064 (-7890 5250);
PAINT PINK (-7890 5250);
DISPLAY INVISIBLE (-7890 5250);
FORCEPROP 2 LAST CDS_LIB mstr_symbols
J 0
(0 0);
DISPLAY 1.361702 (0 0);
PAINT ORANGE (0 0);
DISPLAY INVISIBLE (0 0);
FORCEPROP 2 LAST CDS_XR_PAGE_TITLE CR-168 : @BASEBOARD_FAB2_LIB.BASEBOARD_FAB2(SCH_1):PAGE168
J 0
(-7890 5250);
DISPLAY 0.638298 (-7890 5250);
PAINT PINK (-7890 5250);
DISPLAY INVISIBLE (-7890 5250);
WIRE 16 -1 (-3400 2575)(-3400 2650);
WIRE 16 -1 (-2425 3525)(-2425 3575);
WIRE 16 -1 (-2425 2800)(-2425 2725);
WIRE 16 -1 (-3400 3150)(-3400 3200);
WIRE 16 -1 (-3950 1350)(-3950 1025);
WIRE 16 -1 (-3950 2325)(-3950 2200);
WIRE 16 -1 (-1450 2450)(-1450 2400);
WIRE 3 2175 (-6850 2475)(-6850 750);
WIRE 3 2175 (-6850 750)(-2425 750);
WIRE 3 2175 (-6850 2475)(-2425 2475);
WIRE 3 2175 (-2425 2475)(-2425 750);
WIRE 16 -1 (-7475 2750)(-7175 2750);
FORCEPROP 2 LAST SIG_NAME FM_UART_SWITCH_N
J 0
(-7485 2760);
DISPLAY 0.617021 (-7485 2760);
PAINT ORANGE (-7485 2760);
WIRE 16 -1 (-7175 2750)(-7075 2750);
WIRE 16 -1 (-7175 1450)(-7175 2750);
WIRE 16 -1 (-6050 1450)(-7175 1450);
WIRE 16 -1 (-4100 1450)(-5850 1450);
FORCEPROP 2 LAST SIG_NAME FM_UART_SEL_N
J 0
(-5535 1460);
DISPLAY 0.680851 (-5535 1460);
PAINT ORANGE (-5535 1460);
FORCEPROP 2 LASTPROP $XRERR UNIQUE?
J 0
(-5775 1460);
DISPLAY 0.638298 (-5775 1460);
PAINT MONO (-5775 1460);
DISPLAY INVISIBLE (-5775 1460);
WIRE 16 -1 (-3950 1800)(-3950 1550);
WIRE 16 -1 (-3950 2000)(-3950 1800);
WIRE 16 -1 (-3175 1800)(-3950 1800);
FORCEPROP 2 LAST SIG_NAME FM_SOL_UART_CH_SEL
J 0
(-3710 1810);
DISPLAY 0.617021 (-3710 1810);
PAINT ORANGE (-3710 1810);
WIRE 3 682 (-4900 900)(-4900 1350);
WIRE 3 682 (-4400 900)(-4900 900);
WIRE 3 682 (-4900 1350)(-4400 1350);
WIRE 3 682 (-4400 1350)(-4400 900);
WIRE 16 -1 (-3400 2850)(-3400 2900);
WIRE 16 -1 (-3400 2950)(-3400 2900);
WIRE 16 -1 (-2625 2900)(-3400 2900);
FORCEPROP 2 LAST SIG_NAME FM_DB_PRESENT
J 0
(-3085 2910);
DISPLAY 0.617021 (-3085 2910);
PAINT ORANGE (-3085 2910);
FORCEPROP 2 LASTPROP $XRERR UNIQUE?
J 0
(-3325 2910);
DISPLAY 0.638298 (-3325 2910);
PAINT MONO (-3325 2910);
DISPLAY INVISIBLE (-3325 2910);
WIRE 16 -1 (-4125 2750)(-3550 2750);
FORCEPROP 2 LAST SIG_NAME FM_DB_UART_SEL4_N
J 0
(-4085 2760);
DISPLAY 0.617021 (-4085 2760);
PAINT ORANGE (-4085 2760);
FORCEPROP 2 LASTPROP $XRERR UNIQUE?
J 0
(-4325 2760);
DISPLAY 0.638298 (-4325 2760);
PAINT MONO (-4325 2760);
DISPLAY INVISIBLE (-4325 2760);
WIRE 16 -1 (-4875 2750)(-4325 2750);
FORCEPROP 2 LAST SIG_NAME FM_DB_UART_SEL3_N
J 0
(-4860 2760);
DISPLAY 0.617021 (-4860 2760);
PAINT ORANGE (-4860 2760);
FORCEPROP 2 LASTPROP $XRERR UNIQUE?
J 0
(-5100 2760);
DISPLAY 0.638298 (-5100 2760);
PAINT MONO (-5100 2760);
DISPLAY INVISIBLE (-5100 2760);
WIRE 3 682 (-1800 2950)(-1800 2250);
WIRE 3 682 (-900 2950)(-1800 2950);
WIRE 3 682 (-1800 2250)(-900 2250);
WIRE 3 682 (-900 2250)(-900 2950);
WIRE 16 -1 (-2425 3200)(-2425 3225);
WIRE 16 -1 (-2425 3325)(-2425 3225);
WIRE 16 -1 (-2425 3225)(-1450 3225);
WIRE 16 -1 (-1450 3225)(-1450 2850);
WIRE 16 -1 (-1450 3225)(-600 3225);
FORCEPROP 2 LAST SIG_NAME FM_POST_CARD_PRES_BMC_N
J 0
(-1410 3235);
DISPLAY 0.617021 (-1410 3235);
PAINT ORANGE (-1410 3235);
WIRE 16 -1 (-6225 2750)(-5775 2750);
FORCEPROP 2 LAST SIG_NAME FM_DB_UART_SEL1_N
J 0
(-6235 2760);
DISPLAY 0.617021 (-6235 2760);
PAINT ORANGE (-6235 2760);
FORCEPROP 2 LASTPROP $XRERR UNIQUE?
J 0
(-6475 2760);
DISPLAY 0.638298 (-6475 2760);
PAINT MONO (-6475 2760);
DISPLAY INVISIBLE (-6475 2760);
WIRE 16 -1 (-5575 2750)(-5075 2750);
FORCEPROP 2 LAST SIG_NAME FM_DB_UART_SEL2_N
J 0
(-5585 2760);
DISPLAY 0.617021 (-5585 2760);
PAINT ORANGE (-5585 2760);
FORCEPROP 2 LASTPROP $XRERR UNIQUE?
J 0
(-5825 2760);
DISPLAY 0.638298 (-5825 2760);
PAINT MONO (-5825 2760);
DISPLAY INVISIBLE (-5825 2760);
WIRE 16 -1 (-6875 2750)(-6425 2750);
FORCEPROP 2 LAST SIG_NAME FM_DB_UART_SEL0_N
J 0
(-6860 2760);
DISPLAY 0.617021 (-6860 2760);
PAINT ORANGE (-6860 2760);
FORCEPROP 2 LASTPROP $XRERR UNIQUE?
J 0
(-7100 2760);
DISPLAY 0.638298 (-7100 2760);
PAINT MONO (-7100 2760);
DISPLAY INVISIBLE (-7100 2760);
WIRE 16 -1 (-1525 4625)(-1525 4725);
WIRE 16 -1 (-1525 4725)(-800 4725);
FORCEPROP 2 LAST SIG_NAME TP_FET_Q56_3
J 0
(-1385 4735);
DISPLAY 0.617021 (-1385 4735);
PAINT ORANGE (-1385 4735);
FORCEPROP 2 LASTPROP $XRERR UNIQUE?
J 0
(-770 4725);
DISPLAY 0.638298 (-770 4725);
PAINT MONO (-770 4725);
DISPLAY INVISIBLE (-770 4725);
WIRE 16 -1 (-1725 4325)(-1925 4325);
WIRE 16 -1 (-1925 4325)(-1925 4025);
WIRE 16 -1 (-1925 4025)(-1525 4025);
WIRE 16 -1 (-1525 4225)(-1525 4025);
WIRE 16 -1 (-775 4025)(-1525 4025);
FORCEPROP 2 LAST SIG_NAME TP_FET_Q56_4
J 0
(-1385 4035);
DISPLAY 0.617021 (-1385 4035);
PAINT ORANGE (-1385 4035);
FORCEPROP 2 LASTPROP $XRERR UNIQUE?
J 0
(-745 4025);
DISPLAY 0.638298 (-745 4025);
PAINT MONO (-745 4025);
DISPLAY INVISIBLE (-745 4025);
WIRE 16 -1 (-2425 2550)(-1650 2550);
FORCEPROP 2 LAST SIG_NAME DEBUG_CARD2_PRSNT
J 0
(-2410 2560);
DISPLAY 0.680851 (-2410 2560);
PAINT ORANGE (-2410 2560);
DOT 1 (-3950 1800);
DOT 1 (-1450 3225);
DOT 1 (-2425 3225);
DOT 1 (-1525 4025);
DOT 1 (-7175 2750);
DOT 1 (-3400 2900);
FORCENOTE
TP FAB3 CHANGE UART SELECT CIRCUIT 0926
(-6875 625) 0;
DISPLAY LEFT (-6875 625);
DISPLAY 1.021277 (-6875 625);
PAINT RED (-6875 625);
FORCENOTE
TP FAB3 CHANGE DIODE TO RES 0920
(-5150 825) 0;
DISPLAY LEFT (-5150 825);
DISPLAY 1.021277 (-5150 825);
PAINT RED (-5150 825);
FORCENOTE
TP FAB1 ADD FOR UART SELECT 1117 
(-6875 675) 0;
DISPLAY LEFT (-6875 675);
DISPLAY 1.021277 (-6875 675);
PAINT RED (-6875 675);
FORCENOTE
TP FAB3 DELETE RES 0920
(-5150 775) 0;
DISPLAY LEFT (-5150 775);
DISPLAY 1.021277 (-5150 775);
PAINT RED (-5150 775);
QUIT
